#ISCELL
  mstr_misc dns *
  *
#ISCELL
  pure_quanta quanta_title_block_c *
  *
#ISCELL
  pure_quanta_power universal_gnd *
  page180_i1
#ISCELL
  pure_quanta_power vcc_core *
  page180_i100
#ISCELL
  pure_quanta_power vcc_core *
  page180_i101
#CELL
  pure_quanta q_cap *
  page180_i105
#CELL
  pure_quanta q_cap *
  page180_i106
#CELL
  pure_quanta q_res *
  page180_i107
#CELL
  pure_quanta q_res *
  page180_i108
#CELL
  pure_quanta q_cap *
  page180_i109
#CELL
  pure_quanta q_cap *
  page180_i110
#CELL
  pure_quanta q_inductor4p_14 *
  page180_i111
#CELL
  pure_quanta q_inductor4p_14 *
  page180_i112
#CELL
  pure_quanta q_res *
  page180_i113
#CELL
  pure_quanta q_capp *
  page180_i115
#ISCELL
  standard offpage *
  page180_i116
#ISCELL
  standard offpage *
  page180_i117
#CELL
  pure_quanta q_capp *
  page180_i118
#CELL
  pure_quanta q_cap *
  page180_i119
#CELL
  pure_quanta q_cap *
  page180_i120
#CELL
  pure_quanta q_cap *
  page180_i121
#ISCELL
  pure_quanta_power universal_gnd *
  page180_i122
#ISCELL
  pure_quanta_power universal_gnd *
  page180_i123
#CELL
  pure_quanta q_res *
  page180_i124
#CELL
  pure_quanta q_cap *
  page180_i125
#CELL
  pure_quanta q_cap *
  page180_i127
#ISCELL
  pure_quanta_power universal_gnd *
  page180_i128
#ISCELL
  pure_quanta_power universal_gnd *
  page180_i129
#ISCELL
  pure_quanta_power universal_gnd *
  page180_i13
#CELL
  pure_quanta q_res *
  page180_i130
#CELL
  pure_quanta q_cap *
  page180_i131
#ISCELL
  pure_quanta_power universal_gnd *
  page180_i133
#ISCELL
  pure_quanta_power universal_gnd *
  page180_i134
#ISCELL
  standard offpage *
  page180_i135
#ISCELL
  pure_quanta_power universal_gnd *
  page180_i136
#CELL
  pure_quanta q_res *
  page180_i137
#CELL
  pure_quanta q_cap *
  page180_i138
#ISCELL
  pure_quanta_power universal_gnd *
  page180_i139
#CELL
  pure_quanta q_res *
  page180_i140
#CELL
  pure_quanta q_cap *
  page180_i141
#ISCELL
  pure_quanta_power vcc_core *
  page180_i142
#ISCELL
  pure_quanta_power vcc_core *
  page180_i143
#CELL
  pure_quanta q_res *
  page180_i144
#ISCELL
  standard offpage *
  page180_i145
#ISCELL
  pure_quanta_power universal_gnd *
  page180_i146
#ISCELL
  standard offpage *
  page180_i16
#CELL
  pure_quanta q_res *
  page180_i17
#CELL
  pure_quanta q_res *
  page180_i2
#ISCELL
  standard offpage *
  page180_i20
#ISCELL
  standard offpage *
  page180_i21
#CELL
  pure_quanta isl99390frztr5935 *
  page180_i30
#ISCELL
  pure_quanta_power universal_gnd *
  page180_i31
#ISCELL
  pure_quanta_power universal_gnd *
  page180_i34
#CELL
  pure_quanta isl99390frztr5935 *
  page180_i35
#CELL
  pure_quanta q_cap *
  page180_i39
#ISCELL
  standard offpage *
  page180_i4
#CELL
  pure_quanta q_cap *
  page180_i41
#CELL
  pure_quanta q_cap *
  page180_i42
#ISCELL
  pure_quanta_power universal_gnd *
  page180_i44
#CELL
  pure_quanta q_cap *
  page180_i50
#CELL
  pure_quanta q_res *
  page180_i51
#CELL
  pure_quanta q_cap *
  page180_i52
#CELL
  pure_quanta q_cap *
  page180_i56
#ISCELL
  pure_quanta_power universal_gnd *
  page180_i57
#ISCELL
  standard offpage *
  page180_i6
#CELL
  pure_quanta q_cap *
  page180_i60
#CELL
  pure_quanta q_cap *
  page180_i61
#ISCELL
  pure_quanta_power vcc_core *
  page180_i64
#CELL
  pure_quanta q_capp *
  page180_i66
#ISCELL
  pure_quanta_power universal_gnd *
  page180_i67
#CELL
  pure_quanta q_capp *
  page180_i68
#ISCELL
  pure_quanta_power vcc_core *
  page180_i69
#ISCELL
  standard offpage *
  page180_i7
#CELL
  pure_quanta q_cap *
  page180_i70
#ISCELL
  pure_quanta_power vcc_core *
  page180_i71
#CELL
  pure_quanta q_cap *
  page180_i72
#CELL
  pure_quanta q_cap *
  page180_i73
#CELL
  pure_quanta q_inductor *
  page180_i74
#ISCELL
  pure_quanta_power universal_gnd *
  page180_i75
#ISCELL
  pure_quanta_power vcc_core *
  page180_i76
#ISCELL
  pure_quanta_power universal_gnd *
  page180_i80
#CELL
  pure_quanta q_cap *
  page180_i85
#CELL
  pure_quanta q_cap *
  page180_i86
#ISCELL
  standard offpage *
  page180_i99
